# S9S_MB_2U (Grand Teton) — schematic netlist excerpt (pin names and nets, part order shuffled) for the footprints in the layout excerpt that follows; sources: Cadence DE-HDL packaged netlist, KiCad conversion of 03242023_DA0F0TMBIJ0_F0T_Motherboard_J_brd_V01_OCP.brd

U343  LM4040AIM3X25NOPB  LM4040AIM3X-2.5/NOPB EMPTY  pkg SOT23_123_2-92X1-3  page 306
  \1+\  = OC_P2V5_COMP
  \2-\  = GND
  \3\  = NC

C2247  Q_CAP  1UF 25V 10% X6S  pkg C0402  page 225 : A = P3V3_AUX ; B = GND
R3442  Q_RES  0 5% CHIP  pkg 0402LF  page 144 : A = GPU_PEX_STRAP0 ; B = GND

(kicad_pcb
	(version 20260206)
	(generator "pcbnew")
	(generator_version "10.0")
	(general
		(thickness 1.6)
		(legacy_teardrops no)
	)
	(paper "A4")
	(title_block
		(title "03242023_DA0F0TMBIJ0_F0T_Motherboard_J_brd_V01_OCP.brd")
		(comment 1 "Grand Teton / footprints 3057-3059 of 6105")
	)
	(layers
		(0 "F.Cu" signal "TOP")
		(4 "In1.Cu" signal "GND")
		(6 "In2.Cu" signal "IN1")
		(8 "In3.Cu" signal "GND1")
		(10 "In4.Cu" signal "IN2")
		(12 "In5.Cu" signal "GND2")
		(14 "In6.Cu" signal "IN3")
		(16 "In7.Cu" signal "GND3")
		(18 "In8.Cu" signal "VCC")
		(20 "In9.Cu" signal "VCC1")
		(22 "In10.Cu" signal "GND4")
		(24 "In11.Cu" signal "IN4")
		(26 "In12.Cu" signal "GND5")
		(28 "In13.Cu" signal "IN5")
		(30 "In14.Cu" signal "GND6")
		(32 "In15.Cu" signal "IN6")
		(34 "In16.Cu" signal "GND7")
		(2 "B.Cu" signal "BOTTOM")
		(9 "F.Adhes" user "F.Adhesive")
		(11 "B.Adhes" user "B.Adhesive")
		(13 "F.Paste" user "Package Geometry/Pastemask Top")
		(15 "B.Paste" user "Package Geometry/Pastemask Bottom")
		(5 "F.SilkS" user "Ref Des/Silkscreen Top")
		(7 "B.SilkS" user "Ref Des/Silkscreen Bottom")
		(1 "F.Mask" user "Board Geometry/Soldermask Top")
		(3 "B.Mask" user "Board Geometry/Soldermask Bottom")
		(17 "Dwgs.User" user "User.Drawings")
		(19 "Cmts.User" user "User.Comments")
		(21 "Eco1.User" user "User.Eco1")
		(23 "Eco2.User" user "User.Eco2")
		(25 "Edge.Cuts" user "Board Geometry/Outline")
		(27 "Margin" user)
		(31 "F.CrtYd" user "Package Geometry/Place Bound Top")
		(29 "B.CrtYd" user "Package Geometry/Place Bound Bottom")
		(35 "F.Fab" user "Ref Des/Assembly Top")
		(33 "B.Fab" user "Ref Des/Assembly Bottom")
	)
	(footprint ""
		(layer "F.Cu")
		(at 126.89078 -108.295948 -90)
		(property "Reference" "C2247"
			(at 0 0 270)
			(layer "F.SilkS")
			(hide yes)
			(effects
				(font
					(size 1.27 1.27)
				)
			)
		)
		(property "Value" ""
			(at 0 0 270)
			(layer "F.Fab")
			(effects
				(font
					(size 1.27 1.27)
				)
			)
		)
		(duplicate_pad_numbers_are_jumpers no)
		(fp_line
			(start -0.7874 0.4064)
			(end -0.7874 -0.4064)
			(stroke
				(width 0.1524)
				(type default)
			)
			(layer "F.SilkS")
		)
		(fp_line
			(start 0.7874 0.4064)
			(end -0.7874 0.4064)
			(stroke
				(width 0.1524)
				(type default)
			)
			(layer "F.SilkS")
		)
		(fp_line
			(start -0.7874 -0.4064)
			(end 0.7874 -0.4064)
			(stroke
				(width 0.1524)
				(type default)
			)
			(layer "F.SilkS")
		)
		(fp_line
			(start 0.7874 -0.4064)
			(end 0.7874 0.4064)
			(stroke
				(width 0.1524)
				(type default)
			)
			(layer "F.SilkS")
		)
		(fp_line
			(start -0.67945 0.3048)
			(end -0.67945 -0.305054)
			(stroke
				(width 0.1)
				(type default)
			)
			(layer "F.Fab")
		)
		(fp_line
			(start -0.12065 0.3048)
			(end -0.67945 0.3048)
			(stroke
				(width 0.1)
				(type default)
			)
			(layer "F.Fab")
		)
		(fp_line
			(start 0.120396 0.3048)
			(end 0.120396 0.2794)
			(stroke
				(width 0.1)
				(type default)
			)
			(layer "F.Fab")
		)
		(fp_line
			(start 0.67945 0.3048)
			(end 0.120396 0.3048)
			(stroke
				(width 0.1)
				(type default)
			)
			(layer "F.Fab")
		)
		(fp_line
			(start -0.12065 0.2794)
			(end -0.12065 0.3048)
			(stroke
				(width 0.1)
				(type default)
			)
			(layer "F.Fab")
		)
		(fp_line
			(start 0.120396 0.2794)
			(end -0.12065 0.2794)
			(stroke
				(width 0.1)
				(type default)
			)
			(layer "F.Fab")
		)
		(fp_line
			(start -0.12065 -0.2794)
			(end 0.12065 -0.2794)
			(stroke
				(width 0.1)
				(type default)
			)
			(layer "F.Fab")
		)
		(fp_line
			(start 0.12065 -0.2794)
			(end 0.12065 -0.3048)
			(stroke
				(width 0.1)
				(type default)
			)
			(layer "F.Fab")
		)
		(fp_line
			(start 0.12065 -0.3048)
			(end 0.67945 -0.3048)
			(stroke
				(width 0.1)
				(type default)
			)
			(layer "F.Fab")
		)
		(fp_line
			(start 0.67945 -0.3048)
			(end 0.67945 0.3048)
			(stroke
				(width 0.1)
				(type default)
			)
			(layer "F.Fab")
		)
		(fp_line
			(start -0.67945 -0.305054)
			(end -0.12065 -0.305054)
			(stroke
				(width 0.1)
				(type default)
			)
			(layer "F.Fab")
		)
		(fp_line
			(start -0.12065 -0.305054)
			(end -0.12065 -0.2794)
			(stroke
				(width 0.1)
				(type default)
			)
			(layer "F.Fab")
		)
		(pad "1" smd circle
			(at -0.40005 0 270)
			(size 0 0)
			(layers "F.Cu" "F.Mask" "F.Paste")
			(net "P3V3_AUX")
		)
		(pad "2" smd circle
			(at 0.40005 0 270)
			(size 0 0)
			(layers "F.Cu" "F.Mask" "F.Paste")
			(net "GND")
		)
	)
	(footprint ""
		(layer "F.Cu")
		(at 18.753582 -428.049436 90)
		(property "Reference" "R3442"
			(at 0 0 90)
			(layer "F.SilkS")
			(hide yes)
			(effects
				(font
					(size 1.27 1.27)
				)
			)
		)
		(property "Value" ""
			(at 0 0 90)
			(layer "F.Fab")
			(effects
				(font
					(size 1.27 1.27)
				)
			)
		)
		(duplicate_pad_numbers_are_jumpers no)
		(fp_line
			(start 0.7874 -0.4064)
			(end 0.7874 0.4064)
			(stroke
				(width 0.1524)
				(type default)
			)
			(layer "F.SilkS")
		)
		(fp_line
			(start -0.7874 -0.4064)
			(end 0.7874 -0.4064)
			(stroke
				(width 0.1524)
				(type default)
			)
			(layer "F.SilkS")
		)
		(fp_line
			(start 0.7874 0.4064)
			(end -0.7874 0.4064)
			(stroke
				(width 0.1524)
				(type default)
			)
			(layer "F.SilkS")
		)
		(fp_line
			(start -0.7874 0.4064)
			(end -0.7874 -0.4064)
			(stroke
				(width 0.1524)
				(type default)
			)
			(layer "F.SilkS")
		)
		(fp_line
			(start -0.12065 -0.305054)
			(end -0.12065 -0.2794)
			(stroke
				(width 0.1)
				(type default)
			)
			(layer "F.Fab")
		)
		(fp_line
			(start -0.67945 -0.305054)
			(end -0.12065 -0.305054)
			(stroke
				(width 0.1)
				(type default)
			)
			(layer "F.Fab")
		)
		(fp_line
			(start 0.67945 -0.3048)
			(end 0.67945 0.3048)
			(stroke
				(width 0.1)
				(type default)
			)
			(layer "F.Fab")
		)
		(fp_line
			(start 0.12065 -0.3048)
			(end 0.67945 -0.3048)
			(stroke
				(width 0.1)
				(type default)
			)
			(layer "F.Fab")
		)
		(fp_line
			(start 0.12065 -0.2794)
			(end 0.12065 -0.3048)
			(stroke
				(width 0.1)
				(type default)
			)
			(layer "F.Fab")
		)
		(fp_line
			(start -0.12065 -0.2794)
			(end 0.12065 -0.2794)
			(stroke
				(width 0.1)
				(type default)
			)
			(layer "F.Fab")
		)
		(fp_line
			(start 0.120396 0.2794)
			(end -0.12065 0.2794)
			(stroke
				(width 0.1)
				(type default)
			)
			(layer "F.Fab")
		)
		(fp_line
			(start -0.12065 0.2794)
			(end -0.12065 0.3048)
			(stroke
				(width 0.1)
				(type default)
			)
			(layer "F.Fab")
		)
		(fp_line
			(start 0.67945 0.3048)
			(end 0.120396 0.3048)
			(stroke
				(width 0.1)
				(type default)
			)
			(layer "F.Fab")
		)
		(fp_line
			(start 0.120396 0.3048)
			(end 0.120396 0.2794)
			(stroke
				(width 0.1)
				(type default)
			)
			(layer "F.Fab")
		)
		(fp_line
			(start -0.12065 0.3048)
			(end -0.67945 0.3048)
			(stroke
				(width 0.1)
				(type default)
			)
			(layer "F.Fab")
		)
		(fp_line
			(start -0.67945 0.3048)
			(end -0.67945 -0.305054)
			(stroke
				(width 0.1)
				(type default)
			)
			(layer "F.Fab")
		)
		(pad "1" smd circle
			(at -0.40005 0 90)
			(size 0 0)
			(layers "F.Cu" "F.Mask" "F.Paste")
			(net "GPU_PEX_STRAP0")
		)
		(pad "2" smd circle
			(at 0.40005 0 90)
			(size 0 0)
			(layers "F.Cu" "F.Mask" "F.Paste")
			(net "GND")
		)
	)
	(footprint ""
		(layer "F.Cu")
		(at 183.66486 -422.58742 90)
		(property "Reference" "U343"
			(at -2.11074 2.34569 90)
			(unlocked yes)
			(layer "F.SilkS")
			(effects
				(font
					(size 0.7874 0.5842)
					(thickness 0.1524)
				)
				(justify left)
			)
		)
		(property "Value" ""
			(at 0 0 90)
			(layer "F.Fab")
			(effects
				(font
					(size 1.27 1.27)
				)
			)
		)
		(duplicate_pad_numbers_are_jumpers no)
		(fp_line
			(start 1.868424 -1.519936)
			(end -1.868424 -1.519936)
			(stroke
				(width 0.1524)
				(type default)
			)
			(layer "F.SilkS")
		)
		(fp_line
			(start -1.868424 -1.519936)
			(end -1.868424 1.519936)
			(stroke
				(width 0.1524)
				(type default)
			)
			(layer "F.SilkS")
		)
		(fp_line
			(start 1.868424 1.519936)
			(end 1.868424 -1.519936)
			(stroke
				(width 0.1524)
				(type default)
			)
			(layer "F.SilkS")
		)
		(fp_line
			(start -1.868424 1.519936)
			(end 1.868424 1.519936)
			(stroke
				(width 0.1524)
				(type default)
			)
			(layer "F.SilkS")
		)
		(fp_line
			(start 0.700024 -1.519936)
			(end -0.700024 -1.519936)
			(stroke
				(width 0.1)
				(type default)
			)
			(layer "F.Fab")
		)
		(fp_line
			(start -0.700024 -1.519936)
			(end -0.700024 1.519936)
			(stroke
				(width 0.1)
				(type default)
			)
			(layer "F.Fab")
		)
		(fp_line
			(start 0.700024 1.519936)
			(end 0.700024 -1.519936)
			(stroke
				(width 0.1)
				(type default)
			)
			(layer "F.Fab")
		)
		(fp_line
			(start -0.700024 1.519936)
			(end 0.700024 1.519936)
			(stroke
				(width 0.1)
				(type default)
			)
			(layer "F.Fab")
		)
		(pad "1" smd rect
			(at -1.18491 -0.94996)
			(size 0.6096 1.0668)
			(layers "F.Cu" "F.Mask" "F.Paste")
			(net "OC_P2V5_COMP")
		)
		(pad "2" smd rect
			(at -1.18491 0.94996)
			(size 0.6096 1.0668)
			(layers "F.Cu" "F.Mask" "F.Paste")
			(net "GND")
		)
		(pad "3" smd rect
			(at 1.18491 0)
			(size 0.6096 1.0668)
			(layers "F.Cu" "F.Mask" "F.Paste")
			(net "Net_8629")
		)
	)
)
